FILE_TYPE = MULTI_PHYS_TABLE;

PART 'TPS3895ADRYR'

{========================================================================================}
:VALUE          | PART_TYPE | MATERIAL | PART_NUMBER    = STANDARD | LIFECYCLE      | PART_NUMBER   | JEDEC_TYPE | DESCRIPTION                     | MANUFTR | MANUF_PN       | RD_CMPLS_LVL | CMPLS_LVL | FROM_PJ    | CLASS | DIP_SMD | DATA                   | EE_CHECK_LIST | FP_ECN | PSL | CREATOR | STATUS | MSD  | ESD_CDM | ESD_HBM | ESD_MM | PIN_LENGTH_SHORT_PIN | PIN_LENGTH_LONG_PIN | CREATEDAY  ;
{========================================================================================}
 'TPS3895ADRYR' | 'SMLF'    | 'IC'     | 'AL003895003'(!) = ''       | ''               | 'AL003895003' |'SON6'| 'IC OTHER(6P)TPS3895ADRYR(SON)' | 'TIC'   | 'TPS3895ADRYR' | 'EP(V1)'     | 'EP(V1)'  | 'S2I-ERIC' | 'IC'  | ''      | 'TIC_TPS3895ADRYR.pdf' | ''            | ''     | ''  | ''      | ''     | 'NA' | 'N/A'   | 'N/A'   | 'N/A'  | '0 MILS'             | '0 MILS'            | '20190924'
 'TPS3895ADRYR' | 'SMLF'    | 'EMPTY'  | 'AL003895003'(!) = ''       | ''               | 'AL003895003' |'SON6'| 'IC OTHER(6P)TPS3895ADRYR(SON)' | 'TIC'   | 'TPS3895ADRYR' | 'EP(V1)'     | 'EP(V1)'  | 'S2I-ERIC' | 'IC'  | ''      | 'TIC_TPS3895ADRYR.pdf' | ''            | ''     | ''  | ''      | ''     | 'NA' | 'N/A'   | 'N/A'   | 'N/A'  | '0 MILS'             | '0 MILS'            | '20190924'

END_PART

END.

